# BASEBOARD_FAB2 (Tioga Pass) — schematic netlist excerpt (pin names and nets, part order shuffled) for the footprints in the layout excerpt that follows; sources: Cadence DE-HDL packaged netlist, KiCad conversion of Wiwynn_Tioga_Pass_MB.brd

J1B1  SCONN288_H44441004  SCONN  pkg PIP  page 83
  \12v\(1)  = P12V_NVDIMM_KLM
  VSS(93)  = GND
  DQ(4)  = M_K_DQ<5>
  VSS(92)  = GND
  DQ(0)  = M_K_DQ<1>
  VSS(91)  = GND
  DQS9P  = M_K_DQS_DP<9>
  DQS9N  = M_K_DQS_DN<9>
  VSS(90)  = GND
  DQ(6)  = M_K_DQ<7>
  VSS(89)  = GND
  DQ(2)  = M_K_DQ<3>
  VSS(88)  = GND
  DQ(12)  = M_K_DQ<13>
  VSS(87)  = GND
  DQ(8)  = M_K_DQ<9>
  VSS(86)  = GND
  DQS10P  = M_K_DQS_DP<10>
  DQS10N  = M_K_DQS_DN<10>
  VSS(85)  = GND
  DQ(14)  = M_K_DQ<15>
  VSS(84)  = GND
  DQ(10)  = M_K_DQ<11>
  VSS(83)  = GND
  DQ(20)  = M_K_DQ<21>
  VSS(82)  = GND
  DQ(16)  = M_K_DQ<17>
  VSS(81)  = GND
  DQS11P  = M_K_DQS_DP<11>
  DQS11N  = M_K_DQS_DN<11>
  VSS(80)  = GND
  DQ(22)  = M_K_DQ<23>
  VSS(79)  = GND
  DQ(18)  = M_K_DQ<19>
  VSS(78)  = GND
  DQ(28)  = M_K_DQ<29>
  VSS(77)  = GND
  DQ(24)  = M_K_DQ<25>
  VSS(76)  = GND
  DQS12P  = M_K_DQS_DP<12>
  DQS12N  = M_K_DQS_DN<12>
  VSS(75)  = GND
  DQ(30)  = M_K_DQ<31>
  VSS(74)  = GND
  DQ(26)  = M_K_DQ<27>
  VSS(73)  = GND
  CB(4)  = M_K_ECC<5>
  VSS(72)  = GND
  CB(0)  = M_K_ECC<1>
  VSS(71)  = GND
  DQS17P  = M_K_DQS_DP<17>
  DQS17N  = M_K_DQS_DN<17>
  VSS(70)  = GND
  CB(6)  = M_K_ECC<7>
  VSS(69)  = GND
  CB(2)  = M_K_ECC<3>
  VSS(68)  = GND
  RESET_N  = M_KLM_RST_N
  VDD(25)  = PVDDQ_KLM
  CKE(0)  = M_K_CKE<0>
  VDD(24)  = PVDDQ_KLM
  ACT_N  = M_K_ACT_N
  BG(0)  = M_K_BG<0>
  VDD(23)  = PVDDQ_KLM
  A12  = M_K_MA<12>
  A9  = M_K_MA<9>
  VDD(22)  = PVDDQ_KLM
  A8  = M_K_MA<8>
  A6  = M_K_MA<6>
  VDD(21)  = PVDDQ_KLM
  A3  = M_K_MA<3>
  A1  = M_K_MA<1>
  VDD(20)  = PVDDQ_KLM
  CK0P  = M_K_CLK_DP<0>
  CK0N  = M_K_CLK_DN<0>
  VDD(19)  = PVDDQ_KLM
  VTT(1)  = PVTT_KLM
  EVENT_N  = FM_DIMM_EVENT_COD_N
  A0  = M_K_MA<0>
  VDD(18)  = PVDDQ_KLM
  BA(0)  = M_K_BA<0>
  A16_RAS_N  = M_K_MA<16>
  VDD(17)  = PVDDQ_KLM
  S0_N  = M_K_CS_N<0>
  VDD(16)  = PVDDQ_KLM
  A15_CAS_N  = M_K_MA<15>
  ODT(0)  = M_K_ODT<0>
  VDD(15)  = PVDDQ_KLM
  S1_N  = M_K_CS_N<1>
  VDD(14)  = PVDDQ_KLM
  ODT(1)  = M_K_ODT<1>
  VDD(13)  = PVDDQ_KLM
  S2_N_C(0)  = M_K_CS_N<2>
  VSS(67)  = GND
  DQ(36)  = M_K_DQ<37>
  VSS(66)  = GND
  DQ(32)  = M_K_DQ<33>
  VSS(65)  = GND
  DQS13P  = M_K_DQS_DP<13>
  DQS13N  = M_K_DQS_DN<13>
  VSS(64)  = GND
  DQ(38)  = M_K_DQ<39>
  VSS(63)  = GND
  DQ(34)  = M_K_DQ<35>
  VSS(62)  = GND
  DQ(44)  = M_K_DQ<45>
  VSS(61)  = GND
  DQ(40)  = M_K_DQ<41>
  VSS(60)  = GND
  DQS14P  = M_K_DQS_DP<14>
  DQS14N  = M_K_DQS_DN<14>
  VSS(59)  = GND
  DQ(46)  = M_K_DQ<47>
  VSS(58)  = GND
  DQ(42)  = M_K_DQ<43>
  VSS(57)  = GND
  DQ(52)  = M_K_DQ<53>
  VSS(56)  = GND
  DQ(48)  = M_K_DQ<49>
  VSS(55)  = GND
  DQS15P  = M_K_DQS_DP<15>
  DQS15N  = M_K_DQS_DN<15>
  VSS(54)  = GND
  DQ(54)  = M_K_DQ<55>
  VSS(53)  = GND
  DQ(50)  = M_K_DQ<51>
  VSS(52)  = GND
  DQ(60)  = M_K_DQ<61>
  VSS(51)  = GND
  DQ(56)  = M_K_DQ<57>
  VSS(50)  = GND
  DQS16P  = M_K_DQS_DP<16>
  DQS16N  = M_K_DQS_DN<16>
  VSS(49)  = GND
  DQ(62)  = M_K_DQ<63>
  VSS(48)  = GND
  DQ(58)  = M_K_DQ<59>
  VSS(47)  = GND
  SA(0)  = GND
  SA(1)  = GND
  SCL  = SMB_DDR_KLM_VPP_SCL
  VPP(4)  = PVPP_KLM
  VPP(3)  = PVPP_KLM
  RFU(2)  = TP_CH_K_DIMM_K0_RFU_2
  \12v\(0)  = P12V_NVDIMM_KLM
  VREFCA  = M_K_VREF
  VSS(46)  = GND
  DQ(5)  = M_K_DQ<4>
  VSS(45)  = GND
  DQ(1)  = M_K_DQ<0>
  VSS(44)  = GND
  DQS0N  = M_K_DQS_DN<0>
  DQS0P  = M_K_DQS_DP<0>
  VSS(43)  = GND
  DQ(7)  = M_K_DQ<6>
  VSS(42)  = GND
  DQ(3)  = M_K_DQ<2>
  VSS(41)  = GND
  DQ(13)  = M_K_DQ<12>
  VSS(40)  = GND
  DQ(9)  = M_K_DQ<8>
  VSS(39)  = GND
  DQS1N  = M_K_DQS_DN<1>
  DQS1P  = M_K_DQS_DP<1>
  VSS(38)  = GND
  DQ(15)  = M_K_DQ<14>
  VSS(37)  = GND
  DQ(11)  = M_K_DQ<10>
  VSS(36)  = GND
  DQ(21)  = M_K_DQ<20>
  VSS(35)  = GND
  DQ(17)  = M_K_DQ<16>
  VSS(34)  = GND
  DQS2N  = M_K_DQS_DN<2>
  DQS2P  = M_K_DQS_DP<2>
  VSS(33)  = GND
  DQ(23)  = M_K_DQ<22>
  VSS(32)  = GND
  DQ(19)  = M_K_DQ<18>
  VSS(31)  = GND
  DQ(29)  = M_K_DQ<28>
  VSS(30)  = GND
  DQ(25)  = M_K_DQ<24>
  VSS(29)  = GND
  DQS3N  = M_K_DQS_DN<3>
  DQS3P  = M_K_DQS_DP<3>
  VSS(28)  = GND
  DQ(31)  = M_K_DQ<30>
  VSS(27)  = GND
  DQ(27)  = M_K_DQ<26>
  VSS(26)  = GND
  CB(5)  = M_K_ECC<4>
  VSS(25)  = GND
  CB(1)  = M_K_ECC<0>
  VSS(24)  = GND
  DQS8N  = M_K_DQS_DN<8>
  DQS8P  = M_K_DQS_DP<8>
  VSS(23)  = GND
  CB(7)  = M_K_ECC<6>
  VSS(22)  = GND
  CB(3)  = M_K_ECC<2>
  VSS(21)  = GND
  CKE(1)  = M_K_CKE<1>
  VDD(12)  = PVDDQ_KLM
  RFU(0)  = TP_CH_K_DIMM_K0_RFU_0
  VDD(11)  = PVDDQ_KLM
  BG(1)  = M_K_BG<1>
  ALERT_N  = M_K_ALERT_N
  VDD(10)  = PVDDQ_KLM
  A11  = M_K_MA<11>
  A7  = M_K_MA<7>
  VDD(9)  = PVDDQ_KLM
  A5  = M_K_MA<5>
  A4  = M_K_MA<4>
  VDD(8)  = PVDDQ_KLM
  A2  = M_K_MA<2>
  VDD(7)  = PVDDQ_KLM
  CK1P  = M_K_CLK_DP<1>
  CK1N  = M_K_CLK_DN<1>
  VDD(6)  = PVDDQ_KLM
  VTT(0)  = PVTT_KLM
  PAR  = M_K_PAR
  VDD(5)  = PVDDQ_KLM
  BA(1)  = M_K_BA<1>
  A10  = M_K_MA<10>
  VDD(4)  = PVDDQ_KLM
  RFU(1)  = TP_CH_K_DIMM_K0_RFU_1
  A14_WE_N  = M_K_MA<14>
  VDD(3)  = PVDDQ_KLM
  SAVE_N_NC  = FM_ADR_COMPLETE_KLM_N
  VDD(2)  = PVDDQ_KLM
  A13  = M_K_MA<13>
  VDD(1)  = PVDDQ_KLM
  A17  = M_K_MA<17>
  C(2)  = M_K_C<2>
  VDD(0)  = PVDDQ_KLM
  S3_N_C(1)  = M_K_CS_N<3>
  SA(2)  = GND
  VSS(20)  = GND
  DQ(37)  = M_K_DQ<36>
  VSS(19)  = GND
  DQ(33)  = M_K_DQ<32>
  VSS(18)  = GND
  DQS4N  = M_K_DQS_DN<4>
  DQS4P  = M_K_DQS_DP<4>
  VSS(17)  = GND
  DQ(39)  = M_K_DQ<38>
  VSS(16)  = GND
  DQ(35)  = M_K_DQ<34>
  VSS(15)  = GND
  DQ(45)  = M_K_DQ<44>
  VSS(14)  = GND
  DQ(41)  = M_K_DQ<40>
  VSS(13)  = GND
  DQS5N  = M_K_DQS_DN<5>
  DQS5P  = M_K_DQS_DP<5>
  VSS(12)  = GND
  DQ(47)  = M_K_DQ<46>
  VSS(11)  = GND
  DQ(43)  = M_K_DQ<42>
  VSS(10)  = GND
  DQ(53)  = M_K_DQ<52>
  VSS(9)  = GND
  DQ(49)  = M_K_DQ<48>
  VSS(8)  = GND
  DQS6N  = M_K_DQS_DN<6>
  DQS6P  = M_K_DQS_DP<6>
  VSS(7)  = GND
  DQ(55)  = M_K_DQ<54>
  VSS(6)  = GND
  DQ(51)  = M_K_DQ<50>
  VSS(5)  = GND
  DQ(61)  = M_K_DQ<60>
  VSS(4)  = GND
  DQ(57)  = M_K_DQ<56>
  VSS(3)  = GND
  DQS7N  = M_K_DQS_DN<7>
  DQS7P  = M_K_DQS_DP<7>
  VSS(2)  = GND
  DQ(63)  = M_K_DQ<62>
  VSS(1)  = GND
  DQ(59)  = M_K_DQ<58>
  VSS(0)  = GND
  VDDSPD  = PVPP_KLM
  SDA  = SMB_DDR_KLM_VPP_SDA
  VPP(1)  = PVPP_KLM
  VPP(0)  = PVPP_KLM
  VPP(2)  = PVPP_KLM

(kicad_pcb
	(version 20260206)
	(generator "pcbnew")
	(generator_version "10.0")
	(general
		(thickness 1.6)
		(legacy_teardrops no)
	)
	(paper "A4")
	(title_block
		(title "Wiwynn_Tioga_Pass_MB.brd")
		(comment 1 "Tioga Pass / footprint 320 of 4770 (J1B1), pads 203-251 of 291")
	)
	(layers
		(0 "F.Cu" signal "TOP")
		(4 "In1.Cu" signal "L2GND")
		(6 "In2.Cu" signal "L3")
		(8 "In3.Cu" signal "L4GND")
		(10 "In4.Cu" signal "L5")
		(12 "In5.Cu" signal "L6GND")
		(14 "In6.Cu" signal "L7VCC")
		(16 "In7.Cu" signal "L8VCC")
		(18 "In8.Cu" signal "L9GND")
		(20 "In9.Cu" signal "L10")
		(22 "In10.Cu" signal "L11GND")
		(24 "In11.Cu" signal "L12")
		(26 "In12.Cu" signal "L13GND")
		(2 "B.Cu" signal "BOTTOM")
		(9 "F.Adhes" user "F.Adhesive")
		(11 "B.Adhes" user "B.Adhesive")
		(13 "F.Paste" user "Package Geometry/Pastemask Top")
		(15 "B.Paste" user "Package Geometry/Pastemask Bottom")
		(5 "F.SilkS" user "Ref Des/Silkscreen Top")
		(7 "B.SilkS" user "Ref Des/Silkscreen Bottom")
		(1 "F.Mask" user "Board Geometry/Soldermask Top")
		(3 "B.Mask" user "Board Geometry/Soldermask Bottom")
		(17 "Dwgs.User" user "User.Drawings")
		(19 "Cmts.User" user "User.Comments")
		(21 "Eco1.User" user "User.Eco1")
		(23 "Eco2.User" user "User.Eco2")
		(25 "Edge.Cuts" user "Board Geometry/Outline")
		(27 "Margin" user)
		(31 "F.CrtYd" user "Package Geometry/Place Bound Top")
		(29 "B.CrtYd" user "Package Geometry/Place Bound Bottom")
		(35 "F.Fab" user "Ref Des/Assembly Top")
		(33 "B.Fab" user "Ref Des/Assembly Bottom")
	)
	(footprint ""
		(layer "F.Cu")
		(at 29.699458 -133.0706 90)
		(property "Reference" "J1B1"
			(at -4.960112 38.372542 0)
			(unlocked yes)
			(layer "F.SilkS")
			(effects
				(font
					(size 0.7874 0.5842)
					(thickness 0.1524)
				)
				(justify left)
			)
		)
		(property "Value" ""
			(at 0 0 90)
			(layer "F.Fab")
			(effects
				(font
					(size 1.27 1.27)
				)
			)
		)
		(duplicate_pad_numbers_are_jumpers no)
		(pad "200" smd rect
			(at 4.59994 46.74997 90)
			(size 1.8034 0.508)
			(layers "F.Cu" "F.Mask" "F.Paste")
			(net "GND")
		)
		(pad "201" smd rect
			(at 4.59994 47.600108 90)
			(size 1.8034 0.508)
			(layers "F.Cu" "F.Mask" "F.Paste")
			(net "M_K_ECC<2>")
		)
		(pad "202" smd rect
			(at 4.59994 48.449992 90)
			(size 1.8034 0.508)
			(layers "F.Cu" "F.Mask" "F.Paste")
			(net "GND")
		)
		(pad "203" smd rect
			(at 4.59994 49.299876 90)
			(size 1.8034 0.508)
			(layers "F.Cu" "F.Mask" "F.Paste")
			(net "M_K_CKE<1>")
		)
		(pad "204" smd rect
			(at 4.59994 50.150014 90)
			(size 1.8034 0.508)
			(layers "F.Cu" "F.Mask" "F.Paste")
			(net "PVDDQ_KLM")
		)
		(pad "205" smd rect
			(at 4.59994 50.999898 90)
			(size 1.8034 0.508)
			(layers "F.Cu" "F.Mask" "F.Paste")
			(net "TP_CH_K_DIMM_K0_RFU_0")
		)
		(pad "206" smd rect
			(at 4.59994 51.850036 90)
			(size 1.8034 0.508)
			(layers "F.Cu" "F.Mask" "F.Paste")
			(net "PVDDQ_KLM")
		)
		(pad "207" smd rect
			(at 4.59994 52.69992 90)
			(size 1.8034 0.508)
			(layers "F.Cu" "F.Mask" "F.Paste")
			(net "M_K_BG<1>")
		)
		(pad "208" smd rect
			(at 4.59994 53.550058 90)
			(size 1.8034 0.508)
			(layers "F.Cu" "F.Mask" "F.Paste")
			(net "M_K_ALERT_N")
		)
		(pad "209" smd rect
			(at 4.59994 54.399942 90)
			(size 1.8034 0.508)
			(layers "F.Cu" "F.Mask" "F.Paste")
			(net "PVDDQ_KLM")
		)
		(pad "210" smd rect
			(at 4.59994 55.25008 90)
			(size 1.8034 0.508)
			(layers "F.Cu" "F.Mask" "F.Paste")
			(net "M_K_MA<11>")
		)
		(pad "211" smd rect
			(at 4.59994 56.099964 90)
			(size 1.8034 0.508)
			(layers "F.Cu" "F.Mask" "F.Paste")
			(net "M_K_MA<7>")
		)
		(pad "212" smd rect
			(at 4.59994 56.950102 90)
			(size 1.8034 0.508)
			(layers "F.Cu" "F.Mask" "F.Paste")
			(net "PVDDQ_KLM")
		)
		(pad "213" smd rect
			(at 4.59994 57.799986 90)
			(size 1.8034 0.508)
			(layers "F.Cu" "F.Mask" "F.Paste")
			(net "M_K_MA<5>")
		)
		(pad "214" smd rect
			(at 4.59994 58.650124 90)
			(size 1.8034 0.508)
			(layers "F.Cu" "F.Mask" "F.Paste")
			(net "M_K_MA<4>")
		)
		(pad "215" smd rect
			(at 4.59994 59.500008 90)
			(size 1.8034 0.508)
			(layers "F.Cu" "F.Mask" "F.Paste")
			(net "PVDDQ_KLM")
		)
		(pad "216" smd rect
			(at 4.59994 60.349892 90)
			(size 1.8034 0.508)
			(layers "F.Cu" "F.Mask" "F.Paste")
			(net "M_K_MA<2>")
		)
		(pad "217" smd rect
			(at 4.59994 61.20003 90)
			(size 1.8034 0.508)
			(layers "F.Cu" "F.Mask" "F.Paste")
			(net "PVDDQ_KLM")
		)
		(pad "218" smd rect
			(at 4.59994 62.049914 90)
			(size 1.8034 0.508)
			(layers "F.Cu" "F.Mask" "F.Paste")
			(net "M_K_CLK_DP<1>")
		)
		(pad "219" smd rect
			(at 4.59994 62.900052 90)
			(size 1.8034 0.508)
			(layers "F.Cu" "F.Mask" "F.Paste")
			(net "M_K_CLK_DN<1>")
		)
		(pad "220" smd rect
			(at 4.59994 63.749936 90)
			(size 1.8034 0.508)
			(layers "F.Cu" "F.Mask" "F.Paste")
			(net "PVDDQ_KLM")
		)
		(pad "221" smd rect
			(at 4.59994 64.600074 90)
			(size 1.8034 0.508)
			(layers "F.Cu" "F.Mask" "F.Paste")
			(net "PVTT_KLM")
		)
		(pad "222" smd rect
			(at 4.59994 70.550024 90)
			(size 1.8034 0.508)
			(layers "F.Cu" "F.Mask" "F.Paste")
			(net "M_K_PAR")
		)
		(pad "223" smd rect
			(at 4.59994 71.399908 90)
			(size 1.8034 0.508)
			(layers "F.Cu" "F.Mask" "F.Paste")
			(net "PVDDQ_KLM")
		)
		(pad "224" smd rect
			(at 4.59994 72.250046 90)
			(size 1.8034 0.508)
			(layers "F.Cu" "F.Mask" "F.Paste")
			(net "M_K_BA<1>")
		)
		(pad "225" smd rect
			(at 4.59994 73.09993 90)
			(size 1.8034 0.508)
			(layers "F.Cu" "F.Mask" "F.Paste")
			(net "M_K_MA<10>")
		)
		(pad "226" smd rect
			(at 4.59994 73.950068 90)
			(size 1.8034 0.508)
			(layers "F.Cu" "F.Mask" "F.Paste")
			(net "PVDDQ_KLM")
		)
		(pad "227" smd rect
			(at 4.59994 74.799952 90)
			(size 1.8034 0.508)
			(layers "F.Cu" "F.Mask" "F.Paste")
			(net "TP_CH_K_DIMM_K0_RFU_1")
		)
		(pad "228" smd rect
			(at 4.59994 75.65009 90)
			(size 1.8034 0.508)
			(layers "F.Cu" "F.Mask" "F.Paste")
			(net "M_K_MA<14>")
		)
		(pad "229" smd rect
			(at 4.59994 76.499974 90)
			(size 1.8034 0.508)
			(layers "F.Cu" "F.Mask" "F.Paste")
			(net "PVDDQ_KLM")
		)
		(pad "230" smd rect
			(at 4.59994 77.350112 90)
			(size 1.8034 0.508)
			(layers "F.Cu" "F.Mask" "F.Paste")
			(net "FM_ADR_COMPLETE_KLM_N")
		)
		(pad "231" smd rect
			(at 4.59994 78.199996 90)
			(size 1.8034 0.508)
			(layers "F.Cu" "F.Mask" "F.Paste")
			(net "PVDDQ_KLM")
		)
		(pad "232" smd rect
			(at 4.59994 79.04988 90)
			(size 1.8034 0.508)
			(layers "F.Cu" "F.Mask" "F.Paste")
			(net "M_K_MA<13>")
		)
		(pad "233" smd rect
			(at 4.59994 79.900018 90)
			(size 1.8034 0.508)
			(layers "F.Cu" "F.Mask" "F.Paste")
			(net "PVDDQ_KLM")
		)
		(pad "234" smd rect
			(at 4.59994 80.749902 90)
			(size 1.8034 0.508)
			(layers "F.Cu" "F.Mask" "F.Paste")
			(net "M_K_MA<17>")
		)
		(pad "235" smd rect
			(at 4.59994 81.60004 90)
			(size 1.8034 0.508)
			(layers "F.Cu" "F.Mask" "F.Paste")
			(net "M_K_C<2>")
		)
		(pad "236" smd rect
			(at 4.59994 82.449924 90)
			(size 1.8034 0.508)
			(layers "F.Cu" "F.Mask" "F.Paste")
			(net "PVDDQ_KLM")
		)
		(pad "237" smd rect
			(at 4.59994 83.300062 90)
			(size 1.8034 0.508)
			(layers "F.Cu" "F.Mask" "F.Paste")
			(net "M_K_CS_N<3>")
		)
		(pad "238" smd rect
			(at 4.59994 84.149946 90)
			(size 1.8034 0.508)
			(layers "F.Cu" "F.Mask" "F.Paste")
			(net "GND")
		)
		(pad "239" smd rect
			(at 4.59994 85.000084 90)
			(size 1.8034 0.508)
			(layers "F.Cu" "F.Mask" "F.Paste")
			(net "GND")
		)
		(pad "240" smd rect
			(at 4.59994 85.849968 90)
			(size 1.8034 0.508)
			(layers "F.Cu" "F.Mask" "F.Paste")
			(net "M_K_DQ<36>")
		)
		(pad "241" smd rect
			(at 4.59994 86.700106 90)
			(size 1.8034 0.508)
			(layers "F.Cu" "F.Mask" "F.Paste")
			(net "GND")
		)
		(pad "242" smd rect
			(at 4.59994 87.54999 90)
			(size 1.8034 0.508)
			(layers "F.Cu" "F.Mask" "F.Paste")
			(net "M_K_DQ<32>")
		)
		(pad "243" smd rect
			(at 4.59994 88.399874 90)
			(size 1.8034 0.508)
			(layers "F.Cu" "F.Mask" "F.Paste")
			(net "GND")
		)
		(pad "244" smd rect
			(at 4.59994 89.250012 90)
			(size 1.8034 0.508)
			(layers "F.Cu" "F.Mask" "F.Paste")
			(net "M_K_DQS_DN<4>")
		)
		(pad "245" smd rect
			(at 4.59994 90.099896 90)
			(size 1.8034 0.508)
			(layers "F.Cu" "F.Mask" "F.Paste")
			(net "M_K_DQS_DP<4>")
		)
		(pad "246" smd rect
			(at 4.59994 90.950034 90)
			(size 1.8034 0.508)
			(layers "F.Cu" "F.Mask" "F.Paste")
			(net "GND")
		)
		(pad "247" smd rect
			(at 4.59994 91.799918 90)
			(size 1.8034 0.508)
			(layers "F.Cu" "F.Mask" "F.Paste")
			(net "M_K_DQ<38>")
		)
		(pad "248" smd rect
			(at 4.59994 92.650056 90)
			(size 1.8034 0.508)
			(layers "F.Cu" "F.Mask" "F.Paste")
			(net "GND")
		)
	)
)
